# T6G (Grand Teton) — schematic netlist excerpt (pin names and nets, part order shuffled) for the footprints in the layout excerpt that follows; sources: Cadence DE-HDL packaged netlist, KiCad conversion of 04192023_DAF0TMB3IC0_F0TG_MB_C_brd_V02_OCP.brd

C81  Q_CAP  0.1UF 25V 10% X7R  pkg 0402  page 182 : A = P3V3_9ZXL045_P0_VDD ; B = GND
R298  Q_RES  1K 1% CHIP  pkg 0402LF  page 93 : A = PWRGD_CHH_CPU0_DIMM ; B = PWRGD_CHGL_CPU0

(kicad_pcb
	(version 20260206)
	(generator "pcbnew")
	(generator_version "10.0")
	(general
		(thickness 1.6)
		(legacy_teardrops no)
	)
	(paper "A4")
	(title_block
		(title "04192023_DAF0TMB3IC0_F0TG_MB_C_brd_V02_OCP.brd")
		(comment 1 "Grand Teton / footprints 5440-5441 of 8354")
	)
	(layers
		(0 "F.Cu" signal "TOP")
		(4 "In1.Cu" signal "GND")
		(6 "In2.Cu" signal "IN1")
		(8 "In3.Cu" signal "GND1")
		(10 "In4.Cu" signal "IN2")
		(12 "In5.Cu" signal "GND2")
		(14 "In6.Cu" signal "IN3")
		(16 "In7.Cu" signal "GND3")
		(18 "In8.Cu" signal "VCC")
		(20 "In9.Cu" signal "VCC1")
		(22 "In10.Cu" signal "GND4")
		(24 "In11.Cu" signal "IN4")
		(26 "In12.Cu" signal "GND5")
		(28 "In13.Cu" signal "IN5")
		(30 "In14.Cu" signal "GND6")
		(32 "In15.Cu" signal "IN6")
		(34 "In16.Cu" signal "GND7")
		(2 "B.Cu" signal "BOTTOM")
		(9 "F.Adhes" user "F.Adhesive")
		(11 "B.Adhes" user "B.Adhesive")
		(13 "F.Paste" user "Package Geometry/Pastemask Top")
		(15 "B.Paste" user "Package Geometry/Pastemask Bottom")
		(5 "F.SilkS" user "Ref Des/Silkscreen Top")
		(7 "B.SilkS" user "Ref Des/Silkscreen Bottom")
		(1 "F.Mask" user "Board Geometry/Soldermask Top")
		(3 "B.Mask" user "Board Geometry/Soldermask Bottom")
		(17 "Dwgs.User" user "User.Drawings")
		(19 "Cmts.User" user "User.Comments")
		(21 "Eco1.User" user "User.Eco1")
		(23 "Eco2.User" user "User.Eco2")
		(25 "Edge.Cuts" user "Board Geometry/Outline")
		(27 "Margin" user)
		(31 "F.CrtYd" user "Package Geometry/Place Bound Top")
		(29 "B.CrtYd" user "Package Geometry/Place Bound Bottom")
		(35 "F.Fab" user "Ref Des/Assembly Top")
		(33 "B.Fab" user "Ref Des/Assembly Bottom")
	)
	(footprint ""
		(layer "B.Cu")
		(at 419.684454 -191.32931 180)
		(property "Reference" "R298"
			(at 0 0 0)
			(layer "B.SilkS")
			(hide yes)
			(effects
				(font
					(size 1.27 1.27)
				)
				(justify mirror)
			)
		)
		(property "Value" ""
			(at 0 0 0)
			(layer "B.Fab")
			(effects
				(font
					(size 1.27 1.27)
				)
				(justify mirror)
			)
		)
		(duplicate_pad_numbers_are_jumpers no)
		(fp_line
			(start 0.7874 0.4064)
			(end 0.7874 -0.4064)
			(stroke
				(width 0.1524)
				(type default)
			)
			(layer "B.SilkS")
		)
		(fp_line
			(start 0.7874 -0.4064)
			(end -0.7874 -0.4064)
			(stroke
				(width 0.1524)
				(type default)
			)
			(layer "B.SilkS")
		)
		(fp_line
			(start -0.7874 0.4064)
			(end 0.7874 0.4064)
			(stroke
				(width 0.1524)
				(type default)
			)
			(layer "B.SilkS")
		)
		(fp_line
			(start -0.7874 -0.4064)
			(end -0.7874 0.4064)
			(stroke
				(width 0.1524)
				(type default)
			)
			(layer "B.SilkS")
		)
		(fp_line
			(start 0.67945 0.3048)
			(end 0.67945 -0.305054)
			(stroke
				(width 0.1)
				(type default)
			)
			(layer "B.Fab")
		)
		(fp_line
			(start 0.67945 -0.305054)
			(end 0.12065 -0.305054)
			(stroke
				(width 0.1)
				(type default)
			)
			(layer "B.Fab")
		)
		(fp_line
			(start 0.12065 0.3048)
			(end 0.67945 0.3048)
			(stroke
				(width 0.1)
				(type default)
			)
			(layer "B.Fab")
		)
		(fp_line
			(start 0.12065 0.2794)
			(end 0.12065 0.3048)
			(stroke
				(width 0.1)
				(type default)
			)
			(layer "B.Fab")
		)
		(fp_line
			(start 0.12065 -0.2794)
			(end -0.12065 -0.2794)
			(stroke
				(width 0.1)
				(type default)
			)
			(layer "B.Fab")
		)
		(fp_line
			(start 0.12065 -0.305054)
			(end 0.12065 -0.2794)
			(stroke
				(width 0.1)
				(type default)
			)
			(layer "B.Fab")
		)
		(fp_line
			(start -0.120396 0.3048)
			(end -0.120396 0.2794)
			(stroke
				(width 0.1)
				(type default)
			)
			(layer "B.Fab")
		)
		(fp_line
			(start -0.120396 0.2794)
			(end 0.12065 0.2794)
			(stroke
				(width 0.1)
				(type default)
			)
			(layer "B.Fab")
		)
		(fp_line
			(start -0.12065 -0.2794)
			(end -0.12065 -0.3048)
			(stroke
				(width 0.1)
				(type default)
			)
			(layer "B.Fab")
		)
		(fp_line
			(start -0.12065 -0.3048)
			(end -0.67945 -0.3048)
			(stroke
				(width 0.1)
				(type default)
			)
			(layer "B.Fab")
		)
		(fp_line
			(start -0.67945 0.3048)
			(end -0.120396 0.3048)
			(stroke
				(width 0.1)
				(type default)
			)
			(layer "B.Fab")
		)
		(fp_line
			(start -0.67945 -0.3048)
			(end -0.67945 0.3048)
			(stroke
				(width 0.1)
				(type default)
			)
			(layer "B.Fab")
		)
		(pad "1" smd circle
			(at 0.40005 0)
			(size 0 0)
			(layers "B.Cu" "B.Mask" "B.Paste")
			(net "PWRGD_CHH_CPU0_DIMM")
		)
		(pad "2" smd circle
			(at -0.40005 0)
			(size 0 0)
			(layers "B.Cu" "B.Mask" "B.Paste")
			(net "PWRGD_CHGL_CPU0")
		)
	)
	(footprint ""
		(layer "B.Cu")
		(at 285.23311 -416.255962 -90)
		(property "Reference" "C81"
			(at 0 0 90)
			(layer "B.SilkS")
			(hide yes)
			(effects
				(font
					(size 1.27 1.27)
				)
				(justify mirror)
			)
		)
		(property "Value" ""
			(at 0 0 90)
			(layer "B.Fab")
			(effects
				(font
					(size 1.27 1.27)
				)
				(justify mirror)
			)
		)
		(duplicate_pad_numbers_are_jumpers no)
		(fp_line
			(start -0.7874 0.4064)
			(end 0.7874 0.4064)
			(stroke
				(width 0.1524)
				(type default)
			)
			(layer "B.SilkS")
		)
		(fp_line
			(start 0.7874 0.4064)
			(end 0.7874 -0.4064)
			(stroke
				(width 0.1524)
				(type default)
			)
			(layer "B.SilkS")
		)
		(fp_line
			(start -0.7874 -0.4064)
			(end -0.7874 0.4064)
			(stroke
				(width 0.1524)
				(type default)
			)
			(layer "B.SilkS")
		)
		(fp_line
			(start 0.7874 -0.4064)
			(end -0.7874 -0.4064)
			(stroke
				(width 0.1524)
				(type default)
			)
			(layer "B.SilkS")
		)
		(fp_line
			(start -0.67945 0.3048)
			(end -0.120396 0.3048)
			(stroke
				(width 0.1)
				(type default)
			)
			(layer "B.Fab")
		)
		(fp_line
			(start -0.120396 0.3048)
			(end -0.120396 0.2794)
			(stroke
				(width 0.1)
				(type default)
			)
			(layer "B.Fab")
		)
		(fp_line
			(start 0.12065 0.3048)
			(end 0.67945 0.3048)
			(stroke
				(width 0.1)
				(type default)
			)
			(layer "B.Fab")
		)
		(fp_line
			(start 0.67945 0.3048)
			(end 0.67945 -0.305054)
			(stroke
				(width 0.1)
				(type default)
			)
			(layer "B.Fab")
		)
		(fp_line
			(start -0.120396 0.2794)
			(end 0.12065 0.2794)
			(stroke
				(width 0.1)
				(type default)
			)
			(layer "B.Fab")
		)
		(fp_line
			(start 0.12065 0.2794)
			(end 0.12065 0.3048)
			(stroke
				(width 0.1)
				(type default)
			)
			(layer "B.Fab")
		)
		(fp_line
			(start -0.12065 -0.2794)
			(end -0.12065 -0.3048)
			(stroke
				(width 0.1)
				(type default)
			)
			(layer "B.Fab")
		)
		(fp_line
			(start 0.12065 -0.2794)
			(end -0.12065 -0.2794)
			(stroke
				(width 0.1)
				(type default)
			)
			(layer "B.Fab")
		)
		(fp_line
			(start -0.67945 -0.3048)
			(end -0.67945 0.3048)
			(stroke
				(width 0.1)
				(type default)
			)
			(layer "B.Fab")
		)
		(fp_line
			(start -0.12065 -0.3048)
			(end -0.67945 -0.3048)
			(stroke
				(width 0.1)
				(type default)
			)
			(layer "B.Fab")
		)
		(fp_line
			(start 0.12065 -0.305054)
			(end 0.12065 -0.2794)
			(stroke
				(width 0.1)
				(type default)
			)
			(layer "B.Fab")
		)
		(fp_line
			(start 0.67945 -0.305054)
			(end 0.12065 -0.305054)
			(stroke
				(width 0.1)
				(type default)
			)
			(layer "B.Fab")
		)
		(pad "1" smd circle
			(at 0.40005 0 90)
			(size 0 0)
			(layers "B.Cu" "B.Mask" "B.Paste")
			(net "P3V3_9ZXL045_P0_VDD")
		)
		(pad "2" smd circle
			(at -0.40005 0 90)
			(size 0 0)
			(layers "B.Cu" "B.Mask" "B.Paste")
			(net "GND")
		)
	)
)
